# S9S_MB_2U (Grand Teton) — schematic netlist excerpt (pin names and nets, part order shuffled) for the footprints in the layout excerpt that follows; sources: Cadence DE-HDL packaged netlist, KiCad conversion of 03242023_DA0F0TMBIJ0_F0T_Motherboard_J_brd_V01_OCP.brd

R3234  Q_RES  33.2 1% CHIP  pkg 0402LF  page 161 : A = OCP_V3_2_AUX_PWR_EN ; B = OCP_V3_2_AUX_PWR_EN_R3
R1721  Q_RES  0 5% CHIP  pkg 0402LF  page 179 : A = XTAL_PCH_RTC2_R ; B = XTAL_PCH_RTC2

(kicad_pcb
	(version 20260206)
	(generator "pcbnew")
	(generator_version "10.0")
	(general
		(thickness 1.6)
		(legacy_teardrops no)
	)
	(paper "A4")
	(title_block
		(title "03242023_DA0F0TMBIJ0_F0T_Motherboard_J_brd_V01_OCP.brd")
		(comment 1 "Grand Teton / footprints 1115-1116 of 6105")
	)
	(layers
		(0 "F.Cu" signal "TOP")
		(4 "In1.Cu" signal "GND")
		(6 "In2.Cu" signal "IN1")
		(8 "In3.Cu" signal "GND1")
		(10 "In4.Cu" signal "IN2")
		(12 "In5.Cu" signal "GND2")
		(14 "In6.Cu" signal "IN3")
		(16 "In7.Cu" signal "GND3")
		(18 "In8.Cu" signal "VCC")
		(20 "In9.Cu" signal "VCC1")
		(22 "In10.Cu" signal "GND4")
		(24 "In11.Cu" signal "IN4")
		(26 "In12.Cu" signal "GND5")
		(28 "In13.Cu" signal "IN5")
		(30 "In14.Cu" signal "GND6")
		(32 "In15.Cu" signal "IN6")
		(34 "In16.Cu" signal "GND7")
		(2 "B.Cu" signal "BOTTOM")
		(9 "F.Adhes" user "F.Adhesive")
		(11 "B.Adhes" user "B.Adhesive")
		(13 "F.Paste" user "Package Geometry/Pastemask Top")
		(15 "B.Paste" user "Package Geometry/Pastemask Bottom")
		(5 "F.SilkS" user "Ref Des/Silkscreen Top")
		(7 "B.SilkS" user "Ref Des/Silkscreen Bottom")
		(1 "F.Mask" user "Board Geometry/Soldermask Top")
		(3 "B.Mask" user "Board Geometry/Soldermask Bottom")
		(17 "Dwgs.User" user "User.Drawings")
		(19 "Cmts.User" user "User.Comments")
		(21 "Eco1.User" user "User.Eco1")
		(23 "Eco2.User" user "User.Eco2")
		(25 "Edge.Cuts" user "Board Geometry/Outline")
		(27 "Margin" user)
		(31 "F.CrtYd" user "Package Geometry/Place Bound Top")
		(29 "B.CrtYd" user "Package Geometry/Place Bound Bottom")
		(35 "F.Fab" user "Ref Des/Assembly Top")
		(33 "B.Fab" user "Ref Des/Assembly Bottom")
	)
	(footprint ""
		(layer "F.Cu")
		(at 152.70988 -105.755948 180)
		(property "Reference" "R3234"
			(at 0 0 180)
			(layer "F.SilkS")
			(hide yes)
			(effects
				(font
					(size 1.27 1.27)
				)
			)
		)
		(property "Value" ""
			(at 0 0 180)
			(layer "F.Fab")
			(effects
				(font
					(size 1.27 1.27)
				)
			)
		)
		(duplicate_pad_numbers_are_jumpers no)
		(fp_line
			(start 0.7874 0.4064)
			(end -0.7874 0.4064)
			(stroke
				(width 0.1524)
				(type default)
			)
			(layer "F.SilkS")
		)
		(fp_line
			(start 0.7874 -0.4064)
			(end 0.7874 0.4064)
			(stroke
				(width 0.1524)
				(type default)
			)
			(layer "F.SilkS")
		)
		(fp_line
			(start -0.7874 0.4064)
			(end -0.7874 -0.4064)
			(stroke
				(width 0.1524)
				(type default)
			)
			(layer "F.SilkS")
		)
		(fp_line
			(start -0.7874 -0.4064)
			(end 0.7874 -0.4064)
			(stroke
				(width 0.1524)
				(type default)
			)
			(layer "F.SilkS")
		)
		(fp_line
			(start 0.67945 0.3048)
			(end 0.120396 0.3048)
			(stroke
				(width 0.1)
				(type default)
			)
			(layer "F.Fab")
		)
		(fp_line
			(start 0.67945 -0.3048)
			(end 0.67945 0.3048)
			(stroke
				(width 0.1)
				(type default)
			)
			(layer "F.Fab")
		)
		(fp_line
			(start 0.12065 -0.2794)
			(end 0.12065 -0.3048)
			(stroke
				(width 0.1)
				(type default)
			)
			(layer "F.Fab")
		)
		(fp_line
			(start 0.12065 -0.3048)
			(end 0.67945 -0.3048)
			(stroke
				(width 0.1)
				(type default)
			)
			(layer "F.Fab")
		)
		(fp_line
			(start 0.120396 0.3048)
			(end 0.120396 0.2794)
			(stroke
				(width 0.1)
				(type default)
			)
			(layer "F.Fab")
		)
		(fp_line
			(start 0.120396 0.2794)
			(end -0.12065 0.2794)
			(stroke
				(width 0.1)
				(type default)
			)
			(layer "F.Fab")
		)
		(fp_line
			(start -0.12065 0.3048)
			(end -0.67945 0.3048)
			(stroke
				(width 0.1)
				(type default)
			)
			(layer "F.Fab")
		)
		(fp_line
			(start -0.12065 0.2794)
			(end -0.12065 0.3048)
			(stroke
				(width 0.1)
				(type default)
			)
			(layer "F.Fab")
		)
		(fp_line
			(start -0.12065 -0.2794)
			(end 0.12065 -0.2794)
			(stroke
				(width 0.1)
				(type default)
			)
			(layer "F.Fab")
		)
		(fp_line
			(start -0.12065 -0.305054)
			(end -0.12065 -0.2794)
			(stroke
				(width 0.1)
				(type default)
			)
			(layer "F.Fab")
		)
		(fp_line
			(start -0.67945 0.3048)
			(end -0.67945 -0.305054)
			(stroke
				(width 0.1)
				(type default)
			)
			(layer "F.Fab")
		)
		(fp_line
			(start -0.67945 -0.305054)
			(end -0.12065 -0.305054)
			(stroke
				(width 0.1)
				(type default)
			)
			(layer "F.Fab")
		)
		(pad "1" smd circle
			(at -0.40005 0 180)
			(size 0 0)
			(layers "F.Cu" "F.Mask" "F.Paste")
			(net "OCP_V3_2_AUX_PWR_EN")
		)
		(pad "2" smd circle
			(at 0.40005 0 180)
			(size 0 0)
			(layers "F.Cu" "F.Mask" "F.Paste")
			(net "OCP_V3_2_AUX_PWR_EN_R3")
		)
	)
	(footprint ""
		(layer "F.Cu")
		(at 327.29678 -34.201608 45)
		(property "Reference" "R1721"
			(at 0 0 45)
			(layer "F.SilkS")
			(hide yes)
			(effects
				(font
					(size 1.27 1.27)
				)
			)
		)
		(property "Value" ""
			(at 0 0 45)
			(layer "F.Fab")
			(effects
				(font
					(size 1.27 1.27)
				)
			)
		)
		(duplicate_pad_numbers_are_jumpers no)
		(fp_line
			(start -0.787389 -0.406267)
			(end 0.787389 -0.406267)
			(stroke
				(width 0.1524)
				(type default)
			)
			(layer "F.SilkS")
		)
		(fp_line
			(start -0.787389 0.406267)
			(end -0.787389 -0.406267)
			(stroke
				(width 0.1524)
				(type default)
			)
			(layer "F.SilkS")
		)
		(fp_line
			(start 0.787389 -0.406267)
			(end 0.787389 0.406267)
			(stroke
				(width 0.1524)
				(type default)
			)
			(layer "F.SilkS")
		)
		(fp_line
			(start 0.787389 0.406267)
			(end -0.787389 0.406267)
			(stroke
				(width 0.1524)
				(type default)
			)
			(layer "F.SilkS")
		)
		(fp_line
			(start -0.679446 -0.305149)
			(end -0.120695 -0.304969)
			(stroke
				(width 0.1)
				(type default)
			)
			(layer "F.Fab")
		)
		(fp_line
			(start -0.120695 -0.304969)
			(end -0.120695 -0.279466)
			(stroke
				(width 0.1)
				(type default)
			)
			(layer "F.Fab")
		)
		(fp_line
			(start -0.120695 -0.279466)
			(end 0.120695 -0.279466)
			(stroke
				(width 0.1)
				(type default)
			)
			(layer "F.Fab")
		)
		(fp_line
			(start -0.679446 0.30479)
			(end -0.679446 -0.305149)
			(stroke
				(width 0.1)
				(type default)
			)
			(layer "F.Fab")
		)
		(fp_line
			(start 0.120515 -0.30479)
			(end 0.679446 -0.30479)
			(stroke
				(width 0.1)
				(type default)
			)
			(layer "F.Fab")
		)
		(fp_line
			(start 0.120695 -0.279466)
			(end 0.120515 -0.30479)
			(stroke
				(width 0.1)
				(type default)
			)
			(layer "F.Fab")
		)
		(fp_line
			(start -0.120695 0.279466)
			(end -0.120515 0.30479)
			(stroke
				(width 0.1)
				(type default)
			)
			(layer "F.Fab")
		)
		(fp_line
			(start -0.120515 0.30479)
			(end -0.679446 0.30479)
			(stroke
				(width 0.1)
				(type default)
			)
			(layer "F.Fab")
		)
		(fp_line
			(start 0.679446 -0.30479)
			(end 0.679446 0.30479)
			(stroke
				(width 0.1)
				(type default)
			)
			(layer "F.Fab")
		)
		(fp_line
			(start 0.120335 0.279466)
			(end -0.120695 0.279466)
			(stroke
				(width 0.1)
				(type default)
			)
			(layer "F.Fab")
		)
		(fp_line
			(start 0.120515 0.30479)
			(end 0.120335 0.279466)
			(stroke
				(width 0.1)
				(type default)
			)
			(layer "F.Fab")
		)
		(fp_line
			(start 0.679446 0.30479)
			(end 0.120515 0.30479)
			(stroke
				(width 0.1)
				(type default)
			)
			(layer "F.Fab")
		)
		(pad "1" smd circle
			(at -0.40005 0 45)
			(size 0 0)
			(layers "F.Cu" "F.Mask" "F.Paste")
			(net "XTAL_PCH_RTC2_R")
		)
		(pad "2" smd circle
			(at 0.40005 0 45)
			(size 0 0)
			(layers "F.Cu" "F.Mask" "F.Paste")
			(net "XTAL_PCH_RTC2")
		)
	)
)
